(kicad_pcb
	(version 20260206)
	(generator "pcbnew")
	(generator_version "10.0")
	(general
		(thickness 1.6)
		(legacy_teardrops no)
	)
	(paper "A4")
	(title_block
		(title "03242023_DA0F0TMBIJ0_F0T_Motherboard_J_brd_V01_OCP.brd")
		(comment 1 "Grand Teton / footprints 529-533 of 6105")
	)
	(layers
		(0 "F.Cu" signal "TOP")
		(4 "In1.Cu" signal "GND")
		(6 "In2.Cu" signal "IN1")
		(8 "In3.Cu" signal "GND1")
		(10 "In4.Cu" signal "IN2")
		(12 "In5.Cu" signal "GND2")
		(14 "In6.Cu" signal "IN3")
		(16 "In7.Cu" signal "GND3")
		(18 "In8.Cu" signal "VCC")
		(20 "In9.Cu" signal "VCC1")
		(22 "In10.Cu" signal "GND4")
		(24 "In11.Cu" signal "IN4")
		(26 "In12.Cu" signal "GND5")
		(28 "In13.Cu" signal "IN5")
		(30 "In14.Cu" signal "GND6")
		(32 "In15.Cu" signal "IN6")
		(34 "In16.Cu" signal "GND7")
		(2 "B.Cu" signal "BOTTOM")
		(9 "F.Adhes" user "F.Adhesive")
		(11 "B.Adhes" user "B.Adhesive")
		(13 "F.Paste" user "Package Geometry/Pastemask Top")
		(15 "B.Paste" user "Package Geometry/Pastemask Bottom")
		(5 "F.SilkS" user "Ref Des/Silkscreen Top")
		(7 "B.SilkS" user "Ref Des/Silkscreen Bottom")
		(1 "F.Mask" user "Board Geometry/Soldermask Top")
		(3 "B.Mask" user "Board Geometry/Soldermask Bottom")
		(17 "Dwgs.User" user "User.Drawings")
		(19 "Cmts.User" user "User.Comments")
		(21 "Eco1.User" user "User.Eco1")
		(23 "Eco2.User" user "User.Eco2")
		(25 "Edge.Cuts" user "Board Geometry/Outline")
		(27 "Margin" user)
		(31 "F.CrtYd" user "Package Geometry/Place Bound Top")
		(29 "B.CrtYd" user "Package Geometry/Place Bound Bottom")
		(35 "F.Fab" user "Ref Des/Assembly Top")
		(33 "B.Fab" user "Ref Des/Assembly Bottom")
	)
	(footprint ""
		(layer "F.Cu")
		(at 308.364128 -408.517344 -90)
		(property "Reference" "C904"
			(at 0 0 270)
			(layer "F.SilkS")
			(hide yes)
			(effects
				(font
					(size 1.27 1.27)
				)
			)
		)
		(property "Value" ""
			(at 0 0 270)
			(layer "F.Fab")
			(effects
				(font
					(size 1.27 1.27)
				)
			)
		)
		(duplicate_pad_numbers_are_jumpers no)
		(fp_line
			(start -0.299974 0.150114)
			(end -0.299974 -0.150114)
			(stroke
				(width 0.1)
				(type default)
			)
			(layer "F.Fab")
		)
		(fp_line
			(start 0.299974 0.150114)
			(end -0.299974 0.150114)
			(stroke
				(width 0.1)
				(type default)
			)
			(layer "F.Fab")
		)
		(fp_line
			(start -0.299974 -0.150114)
			(end 0.299974 -0.150114)
			(stroke
				(width 0.1)
				(type default)
			)
			(layer "F.Fab")
		)
		(fp_line
			(start 0.299974 -0.150114)
			(end 0.299974 0.150114)
			(stroke
				(width 0.1)
				(type default)
			)
			(layer "F.Fab")
		)
		(pad "1" smd rect
			(at -0.2667 0 270)
			(size 0.3048 0.381)
			(layers "F.Cu" "F.Mask" "F.Paste")
			(net "P5E_CPU0_PE0_TX_C_DN<14>")
		)
		(pad "2" smd rect
			(at 0.2667 0 270)
			(size 0.3048 0.381)
			(layers "F.Cu" "F.Mask" "F.Paste")
			(net "P5E_CPU0_PE0_TX_DN<14>")
		)
	)
	(footprint ""
		(layer "F.Cu")
		(at 105.21188 -423.763948 180)
		(property "Reference" "R4178"
			(at 0 0 180)
			(layer "F.SilkS")
			(hide yes)
			(effects
				(font
					(size 1.27 1.27)
				)
			)
		)
		(property "Value" ""
			(at 0 0 180)
			(layer "F.Fab")
			(effects
				(font
					(size 1.27 1.27)
				)
			)
		)
		(duplicate_pad_numbers_are_jumpers no)
		(fp_line
			(start 0.7874 0.4064)
			(end -0.7874 0.4064)
			(stroke
				(width 0.1524)
				(type default)
			)
			(layer "F.SilkS")
		)
		(fp_line
			(start 0.7874 -0.4064)
			(end 0.7874 0.4064)
			(stroke
				(width 0.1524)
				(type default)
			)
			(layer "F.SilkS")
		)
		(fp_line
			(start -0.7874 0.4064)
			(end -0.7874 -0.4064)
			(stroke
				(width 0.1524)
				(type default)
			)
			(layer "F.SilkS")
		)
		(fp_line
			(start -0.7874 -0.4064)
			(end 0.7874 -0.4064)
			(stroke
				(width 0.1524)
				(type default)
			)
			(layer "F.SilkS")
		)
		(fp_line
			(start 0.67945 0.3048)
			(end 0.120396 0.3048)
			(stroke
				(width 0.1)
				(type default)
			)
			(layer "F.Fab")
		)
		(fp_line
			(start 0.67945 -0.3048)
			(end 0.67945 0.3048)
			(stroke
				(width 0.1)
				(type default)
			)
			(layer "F.Fab")
		)
		(fp_line
			(start 0.12065 -0.2794)
			(end 0.12065 -0.3048)
			(stroke
				(width 0.1)
				(type default)
			)
			(layer "F.Fab")
		)
		(fp_line
			(start 0.12065 -0.3048)
			(end 0.67945 -0.3048)
			(stroke
				(width 0.1)
				(type default)
			)
			(layer "F.Fab")
		)
		(fp_line
			(start 0.120396 0.3048)
			(end 0.120396 0.2794)
			(stroke
				(width 0.1)
				(type default)
			)
			(layer "F.Fab")
		)
		(fp_line
			(start 0.120396 0.2794)
			(end -0.12065 0.2794)
			(stroke
				(width 0.1)
				(type default)
			)
			(layer "F.Fab")
		)
		(fp_line
			(start -0.12065 0.3048)
			(end -0.67945 0.3048)
			(stroke
				(width 0.1)
				(type default)
			)
			(layer "F.Fab")
		)
		(fp_line
			(start -0.12065 0.2794)
			(end -0.12065 0.3048)
			(stroke
				(width 0.1)
				(type default)
			)
			(layer "F.Fab")
		)
		(fp_line
			(start -0.12065 -0.2794)
			(end 0.12065 -0.2794)
			(stroke
				(width 0.1)
				(type default)
			)
			(layer "F.Fab")
		)
		(fp_line
			(start -0.12065 -0.305054)
			(end -0.12065 -0.2794)
			(stroke
				(width 0.1)
				(type default)
			)
			(layer "F.Fab")
		)
		(fp_line
			(start -0.67945 0.3048)
			(end -0.67945 -0.305054)
			(stroke
				(width 0.1)
				(type default)
			)
			(layer "F.Fab")
		)
		(fp_line
			(start -0.67945 -0.305054)
			(end -0.12065 -0.305054)
			(stroke
				(width 0.1)
				(type default)
			)
			(layer "F.Fab")
		)
		(pad "1" smd circle
			(at -0.40005 0 180)
			(size 0 0)
			(layers "F.Cu" "F.Mask" "F.Paste")
			(net "SMB_LM75_2_3V3AUX_SCL")
		)
		(pad "2" smd circle
			(at 0.40005 0 180)
			(size 0 0)
			(layers "F.Cu" "F.Mask" "F.Paste")
			(net "SMB_LM75_2_3V3AUX_SCL_R1")
		)
	)
	(footprint ""
		(layer "F.Cu")
		(at 114.957606 -354.065586)
		(property "Reference" "PC422"
			(at 0 0 0)
			(layer "F.SilkS")
			(hide yes)
			(effects
				(font
					(size 1.27 1.27)
				)
			)
		)
		(property "Value" ""
			(at 0 0 0)
			(layer "F.Fab")
			(effects
				(font
					(size 1.27 1.27)
				)
			)
		)
		(duplicate_pad_numbers_are_jumpers no)
		(fp_line
			(start -0.7874 -0.4064)
			(end 0.7874 -0.4064)
			(stroke
				(width 0.1524)
				(type default)
			)
			(layer "F.SilkS")
		)
		(fp_line
			(start -0.7874 0.4064)
			(end -0.7874 -0.4064)
			(stroke
				(width 0.1524)
				(type default)
			)
			(layer "F.SilkS")
		)
		(fp_line
			(start 0.7874 -0.4064)
			(end 0.7874 0.4064)
			(stroke
				(width 0.1524)
				(type default)
			)
			(layer "F.SilkS")
		)
		(fp_line
			(start 0.7874 0.4064)
			(end -0.7874 0.4064)
			(stroke
				(width 0.1524)
				(type default)
			)
			(layer "F.SilkS")
		)
		(fp_line
			(start -0.67945 -0.305054)
			(end -0.12065 -0.305054)
			(stroke
				(width 0.1)
				(type default)
			)
			(layer "F.Fab")
		)
		(fp_line
			(start -0.67945 0.3048)
			(end -0.67945 -0.305054)
			(stroke
				(width 0.1)
				(type default)
			)
			(layer "F.Fab")
		)
		(fp_line
			(start -0.12065 -0.305054)
			(end -0.12065 -0.2794)
			(stroke
				(width 0.1)
				(type default)
			)
			(layer "F.Fab")
		)
		(fp_line
			(start -0.12065 -0.2794)
			(end 0.12065 -0.2794)
			(stroke
				(width 0.1)
				(type default)
			)
			(layer "F.Fab")
		)
		(fp_line
			(start -0.12065 0.2794)
			(end -0.12065 0.3048)
			(stroke
				(width 0.1)
				(type default)
			)
			(layer "F.Fab")
		)
		(fp_line
			(start -0.12065 0.3048)
			(end -0.67945 0.3048)
			(stroke
				(width 0.1)
				(type default)
			)
			(layer "F.Fab")
		)
		(fp_line
			(start 0.120396 0.2794)
			(end -0.12065 0.2794)
			(stroke
				(width 0.1)
				(type default)
			)
			(layer "F.Fab")
		)
		(fp_line
			(start 0.120396 0.3048)
			(end 0.120396 0.2794)
			(stroke
				(width 0.1)
				(type default)
			)
			(layer "F.Fab")
		)
		(fp_line
			(start 0.12065 -0.3048)
			(end 0.67945 -0.3048)
			(stroke
				(width 0.1)
				(type default)
			)
			(layer "F.Fab")
		)
		(fp_line
			(start 0.12065 -0.2794)
			(end 0.12065 -0.3048)
			(stroke
				(width 0.1)
				(type default)
			)
			(layer "F.Fab")
		)
		(fp_line
			(start 0.67945 -0.3048)
			(end 0.67945 0.3048)
			(stroke
				(width 0.1)
				(type default)
			)
			(layer "F.Fab")
		)
		(fp_line
			(start 0.67945 0.3048)
			(end 0.120396 0.3048)
			(stroke
				(width 0.1)
				(type default)
			)
			(layer "F.Fab")
		)
		(pad "1" smd circle
			(at -0.40005 0)
			(size 0 0)
			(layers "F.Cu" "F.Mask" "F.Paste")
			(net "SH_PVCCFA_EHV_FIVRA_CPU1_R")
		)
		(pad "2" smd circle
			(at 0.40005 0)
			(size 0 0)
			(layers "F.Cu" "F.Mask" "F.Paste")
			(net "VSENSE_PVCCFA_EHV_FIVRA_CPU1_DN")
		)
	)
	(footprint ""
		(layer "F.Cu")
		(at 33.100518 -122.380502 -90)
		(property "Reference" "R2454"
			(at 0 0 270)
			(layer "F.SilkS")
			(hide yes)
			(effects
				(font
					(size 1.27 1.27)
				)
			)
		)
		(property "Value" ""
			(at 0 0 270)
			(layer "F.Fab")
			(effects
				(font
					(size 1.27 1.27)
				)
			)
		)
		(duplicate_pad_numbers_are_jumpers no)
		(fp_line
			(start -0.7874 0.4064)
			(end -0.7874 -0.4064)
			(stroke
				(width 0.1524)
				(type default)
			)
			(layer "F.SilkS")
		)
		(fp_line
			(start 0.7874 0.4064)
			(end -0.7874 0.4064)
			(stroke
				(width 0.1524)
				(type default)
			)
			(layer "F.SilkS")
		)
		(fp_line
			(start -0.7874 -0.4064)
			(end 0.7874 -0.4064)
			(stroke
				(width 0.1524)
				(type default)
			)
			(layer "F.SilkS")
		)
		(fp_line
			(start 0.7874 -0.4064)
			(end 0.7874 0.4064)
			(stroke
				(width 0.1524)
				(type default)
			)
			(layer "F.SilkS")
		)
		(fp_line
			(start -0.67945 0.3048)
			(end -0.67945 -0.305054)
			(stroke
				(width 0.1)
				(type default)
			)
			(layer "F.Fab")
		)
		(fp_line
			(start -0.12065 0.3048)
			(end -0.67945 0.3048)
			(stroke
				(width 0.1)
				(type default)
			)
			(layer "F.Fab")
		)
		(fp_line
			(start 0.120396 0.3048)
			(end 0.120396 0.2794)
			(stroke
				(width 0.1)
				(type default)
			)
			(layer "F.Fab")
		)
		(fp_line
			(start 0.67945 0.3048)
			(end 0.120396 0.3048)
			(stroke
				(width 0.1)
				(type default)
			)
			(layer "F.Fab")
		)
		(fp_line
			(start -0.12065 0.2794)
			(end -0.12065 0.3048)
			(stroke
				(width 0.1)
				(type default)
			)
			(layer "F.Fab")
		)
		(fp_line
			(start 0.120396 0.2794)
			(end -0.12065 0.2794)
			(stroke
				(width 0.1)
				(type default)
			)
			(layer "F.Fab")
		)
		(fp_line
			(start -0.12065 -0.2794)
			(end 0.12065 -0.2794)
			(stroke
				(width 0.1)
				(type default)
			)
			(layer "F.Fab")
		)
		(fp_line
			(start 0.12065 -0.2794)
			(end 0.12065 -0.3048)
			(stroke
				(width 0.1)
				(type default)
			)
			(layer "F.Fab")
		)
		(fp_line
			(start 0.12065 -0.3048)
			(end 0.67945 -0.3048)
			(stroke
				(width 0.1)
				(type default)
			)
			(layer "F.Fab")
		)
		(fp_line
			(start 0.67945 -0.3048)
			(end 0.67945 0.3048)
			(stroke
				(width 0.1)
				(type default)
			)
			(layer "F.Fab")
		)
		(fp_line
			(start -0.67945 -0.305054)
			(end -0.12065 -0.305054)
			(stroke
				(width 0.1)
				(type default)
			)
			(layer "F.Fab")
		)
		(fp_line
			(start -0.12065 -0.305054)
			(end -0.12065 -0.2794)
			(stroke
				(width 0.1)
				(type default)
			)
			(layer "F.Fab")
		)
		(pad "1" smd circle
			(at -0.40005 0 270)
			(size 0 0)
			(layers "F.Cu" "F.Mask" "F.Paste")
			(net "SMB_VR_3V3AUX_SDA_R")
		)
		(pad "2" smd circle
			(at 0.40005 0 270)
			(size 0 0)
			(layers "F.Cu" "F.Mask" "F.Paste")
			(net "SMB_VR_3V3AUX_SDA_R2")
		)
	)
	(footprint ""
		(layer "F.Cu")
		(at 418.48024 -153.069036 -90)
		(property "Reference" "PU42"
			(at -0.493522 -6.4643 0)
			(unlocked yes)
			(layer "F.SilkS")
			(effects
				(font
					(size 0.7874 0.5842)
					(thickness 0.1524)
				)
				(justify left)
			)
		)
		(property "Value" ""
			(at 0 0 270)
			(layer "F.Fab")
			(effects
				(font
					(size 1.27 1.27)
				)
			)
		)
		(duplicate_pad_numbers_are_jumpers no)
		(fp_line
			(start -2.050034 2.549906)
			(end -1.27 2.549906)
			(stroke
				(width 0.1524)
				(type default)
			)
			(layer "F.SilkS")
		)
		(fp_line
			(start 1.27 2.549906)
			(end 2.050034 2.549906)
			(stroke
				(width 0.1524)
				(type default)
			)
			(layer "F.SilkS")
		)
		(fp_line
			(start 2.050034 2.549906)
			(end 2.050034 1.88976)
			(stroke
				(width 0.1524)
				(type default)
			)
			(layer "F.SilkS")
		)
		(fp_line
			(start -2.050034 1.88976)
			(end -2.050034 2.549906)
			(stroke
				(width 0.1524)
				(type default)
			)
			(layer "F.SilkS")
		)
		(fp_line
			(start -2.050034 0.406654)
			(end -2.050034 0.786384)
			(stroke
				(width 0.1524)
				(type default)
			)
			(layer "F.SilkS")
		)
		(fp_line
			(start 2.050034 0.08636)
			(end 2.050034 -0.178308)
			(stroke
				(width 0.1524)
				(type default)
			)
			(layer "F.SilkS")
		)
		(fp_line
			(start 2.050034 -1.981708)
			(end 2.050034 -2.549906)
			(stroke
				(width 0.1524)
				(type default)
			)
			(layer "F.SilkS")
		)
		(fp_line
			(start -2.050034 -2.549906)
			(end -2.050034 -2.126742)
			(stroke
				(width 0.1524)
				(type default)
			)
			(layer "F.SilkS")
		)
		(fp_line
			(start -1.61671 -2.549906)
			(end -2.050034 -2.549906)
			(stroke
				(width 0.1524)
				(type default)
			)
			(layer "F.SilkS")
		)
		(fp_line
			(start 2.050034 -2.549906)
			(end 1.916684 -2.549906)
			(stroke
				(width 0.1524)
				(type default)
			)
			(layer "F.SilkS")
		)
		(fp_poly
			(pts
				(xy -2.69621 -2.060194) (xy -2.316988 -1.87071) (xy -2.69621 -1.680972)
			)
			(stroke
				(width 0)
				(type default)
			)
			(fill yes)
			(layer "F.SilkS")
		)
		(fp_line
			(start -2.050034 2.549906)
			(end 2.050034 2.549906)
			(stroke
				(width 0.1)
				(type default)
			)
			(layer "F.Fab")
		)
		(fp_line
			(start 2.050034 2.549906)
			(end 2.050034 -2.549906)
			(stroke
				(width 0.1)
				(type default)
			)
			(layer "F.Fab")
		)
		(fp_line
			(start -2.050034 -2.549906)
			(end -2.050034 2.549906)
			(stroke
				(width 0.1)
				(type default)
			)
			(layer "F.Fab")
		)
		(fp_line
			(start 2.050034 -2.549906)
			(end -2.050034 -2.549906)
			(stroke
				(width 0.1)
				(type default)
			)
			(layer "F.Fab")
		)
		(fp_poly
			(pts
				(xy -3.43789 -2.368042) (xy -3.43789 -1.352042) (xy -2.42189 -1.860042)
			)
			(stroke
				(width 0)
				(type default)
			)
			(fill yes)
			(layer "F.Fab")
		)
		(pad "1" smd rect
			(at -1.925066 -1.860042 180)
			(size 0.254 0.5588)
			(layers "F.Cu" "F.Mask" "F.Paste")
			(net "PVCCFA_EHV_CPU0_BTSEN")
		)
		(pad "2" smd rect
			(at -1.925066 -1.359916 180)
			(size 0.254 0.5588)
			(layers "F.Cu" "F.Mask" "F.Paste")
			(net "PVCCFA_EHV_CPU0_FAULT")
		)
		(pad "3" smd rect
			(at -1.925066 -0.860044 180)
			(size 0.254 0.5588)
			(layers "F.Cu" "F.Mask" "F.Paste")
			(net "PVCCFA_EHV_CPU0_NC1")
		)
		(pad "4" smd rect
			(at -1.925066 -0.359918 180)
			(size 0.254 0.5588)
			(layers "F.Cu" "F.Mask" "F.Paste")
			(net "PVCCFA_EHV_CPU0_VDD1")
		)
		(pad "5" smd rect
			(at -1.925066 0.139954 180)
			(size 0.254 0.5588)
			(layers "F.Cu" "F.Mask" "F.Paste")
			(net "PVCCFA_EHV_CPU0_LSET1")
		)
		(pad "6_7-13_15-29" smd circle
			(at 0 0.98806)
			(size 0 0)
			(layers "F.Cu" "F.Mask" "F.Paste")
			(net "GND")
		)
		(pad "8_12" smd rect
			(at 0 2.400046 180)
			(size 0.6096 2.2606)
			(layers "F.Cu" "F.Mask" "F.Paste")
			(net "SW_PVCCFA_EHV_CPU0_SW1")
		)
		(pad "16_18-28" smd rect
			(at 1.480566 -1.080008 270)
			(size 1.4478 1.524)
			(layers "F.Cu" "F.Mask" "F.Paste")
			(net "SW_P12V_PVCCINFAON_CPU0_FLT")
		)
		(pad "19" smd rect
			(at 1.649984 -2.424938 270)
			(size 0.254 0.5588)
			(layers "F.Cu" "F.Mask" "F.Paste")
			(net "SW_PVCCFA_EHV_CPU0_BOOTR1")
		)
		(pad "20" smd rect
			(at 1.150112 -2.424938 270)
			(size 0.254 0.5588)
			(layers "F.Cu" "F.Mask" "F.Paste")
			(net "SW_PVCCFA_EHV_CPU0_BOOT1")
		)
		(pad "21" smd rect
			(at 0.649986 -2.424938 270)
			(size 0.254 0.5588)
			(layers "F.Cu" "F.Mask" "F.Paste")
			(net "PVCCFA_EHV_CPU0_BPWM1")
		)
		(pad "22" smd rect
			(at 0.150114 -2.424938 270)
			(size 0.254 0.5588)
			(layers "F.Cu" "F.Mask" "F.Paste")
			(net "PVCCFA_EHV_CPU0_NC2")
		)
		(pad "23" smd rect
			(at -0.350012 -2.424938 270)
			(size 0.254 0.5588)
			(layers "F.Cu" "F.Mask" "F.Paste")
			(net "GND")
		)
		(pad "24" smd rect
			(at -0.849884 -2.424938 270)
			(size 0.254 0.5588)
			(layers "F.Cu" "F.Mask" "F.Paste")
			(net "PVCCINFAON_CPU0_VREF")
		)
		(pad "25" smd rect
			(at -1.35001 -2.424938 270)
			(size 0.254 0.5588)
			(layers "F.Cu" "F.Mask" "F.Paste")
			(net "PVCCFA_EHV_CPU0_BCSP1")
		)
		(pad "26" smd circle
			(at -0.490728 -1.009396)
			(size 0 0)
			(layers "F.Cu" "F.Mask" "F.Paste")
			(net "GND")
		)
		(pad "27" smd rect
			(at -1.124966 0.425958 180)
			(size 0.2032 0.3556)
			(layers "F.Cu" "F.Mask" "F.Paste")
			(net "Net_8494")
		)
		(zone
			(layer "F.Cu")
			(hatch none 0.5)
			(connect_pads
				(clearance 0)
			)
			(min_thickness 0.25)
			(keepout
				(tracks not_allowed)
				(vias allowed)
				(pads allowed)
				(copperpour not_allowed)
				(footprints allowed)
			)
			(placement
				(enabled no)
				(sheetname "")
			)
			(fill
				(thermal_gap 0.5)
				(thermal_bridge_width 0.5)
				(island_removal_mode 0)
			)
			(polygon
				(pts
					(xy 416.41014 -155.11907) (xy 416.67938 -155.11907) (xy 416.67938 -151.019002) (xy 416.4203 -151.019002)
					(xy 416.4203 -151.887936) (xy 416.435794 -151.887936) (xy 416.435794 -154.250136) (xy 416.41014 -154.250136)
				)
			)
		)
		(zone
			(layer "F.Cu")
			(hatch none 0.5)
			(connect_pads
				(clearance 0)
			)
			(min_thickness 0.25)
			(keepout
				(tracks not_allowed)
				(vias allowed)
				(pads allowed)
				(copperpour not_allowed)
				(footprints allowed)
			)
			(placement
				(enabled no)
				(sheetname "")
			)
			(fill
				(thermal_gap 0.5)
				(thermal_bridge_width 0.5)
				(island_removal_mode 0)
			)
			(polygon
				(pts
					(xy 420.10584 -154.663902) (xy 420.574978 -154.663902) (xy 420.574978 -151.019002) (xy 420.373048 -151.019002)
					(xy 420.373048 -152.36317) (xy 418.747448 -152.36317) (xy 418.747448 -151.019002) (xy 418.30498 -151.019002)
					(xy 418.30498 -152.499568) (xy 418.58946 -152.499568) (xy 418.58946 -152.632156) (xy 420.398448 -152.632156)
					(xy 420.398448 -154.257756) (xy 420.168832 -154.487372) (xy 420.10584 -154.487372)
				)
			)
		)
	)
)
